# S9S_MB_2U (Grand Teton) — schematic netlist excerpt (pin names and nets, part order shuffled) for the footprints in the layout excerpt that follows; sources: Cadence DE-HDL packaged netlist, KiCad conversion of 03242023_DA0F0TMBIJ0_F0T_Motherboard_J_brd_V01_OCP.brd

J19  SCONN288_ADR50017P130CC  SCONN288_ADR50017-P130CC IO  pkg DDR288S_1-1VXB  page 100
  VIN_BULK0  = P12V_S3_AUX_CPU1_NVDIMM
  RFU0  = TP_CHB_CPU1_DIMM1_FRU_0
  VIN_MGMT  = P3V3_AUX
  HSCL  = I3C_SPD_DDRABCD_CPU1_LVC1_SCL_2
  HSDA  = I3C_SPD_DDRABCD_CPU1_LVC1_SDA
  VSS0  = GND
  DQ0_A  = M_B_CPU1_SA_DQ<0>
  VSS1  = GND
  DQ1_A  = M_B_CPU1_SA_DQ<1>
  VSS2  = GND
  DQS0_A_T  = M_B_CPU1_SA_DQS_DP<0>
  DQS0_A_C  = M_B_CPU1_SA_DQS_DN<0>
  VSS3  = GND
  DQ4_A  = M_B_CPU1_SA_DQ<4>
  VSS4  = GND
  DQ5_A  = M_B_CPU1_SA_DQ<5>
  VSS5  = GND
  DQ8_A  = M_B_CPU1_SA_DQ<8>
  VSS6  = GND
  DQ9_A  = M_B_CPU1_SA_DQ<9>
  VSS7  = GND
  DQS1_A_T  = M_B_CPU1_SA_DQS_DP<1>
  DQS1_A_C  = M_B_CPU1_SA_DQS_DN<1>
  VSS8  = GND
  DQ12_A  = M_B_CPU1_SA_DQ<12>
  VSS9  = GND
  DQ13_A  = M_B_CPU1_SA_DQ<13>
  VSS10  = GND
  DQ16_A  = M_B_CPU1_SA_DQ<16>
  VSS11  = GND
  DQ17_A  = M_B_CPU1_SA_DQ<17>
  VSS12  = GND
  DQS2_A_T  = M_B_CPU1_SA_DQS_DP<2>
  DQS2_A_C  = M_B_CPU1_SA_DQS_DN<2>
  VSS13  = GND
  DQ20_A  = M_B_CPU1_SA_DQ<20>
  VSS14  = GND
  DQ21_A  = M_B_CPU1_SA_DQ<21>
  VSS15  = GND
  DQ24_A  = M_B_CPU1_SA_DQ<24>
  VSS16  = GND
  DQ25_A  = M_B_CPU1_SA_DQ<25>
  VSS17  = GND
  DQS3_A_T  = M_B_CPU1_SA_DQS_DP<3>
  DQS3_A_C  = M_B_CPU1_SA_DQS_DN<3>
  VSS18  = GND
  DQ28_A  = M_B_CPU1_SA_DQ<28>
  VSS19  = GND
  DQ29_A  = M_B_CPU1_SA_DQ<29>
  VSS20  = GND
  CB0_A  = M_B_CPU1_SA_CB<0>
  VSS21  = GND
  CB1_A  = M_B_CPU1_SA_CB<1>
  VSS22  = GND
  DQS4_A_T  = M_B_CPU1_SA_DQS_DP<4>
  DQS4_A_C  = M_B_CPU1_SA_DQS_DN<4>
  VSS23  = GND
  CB4_A  = M_B_CPU1_SA_CB<4>
  VSS24  = GND
  CB5_A  = M_B_CPU1_SA_CB<5>
  VSS25  = GND
  ALERT_N  = M_B_CPU1_ALERT_N
  VSS26  = GND
  CS0_A_N  = M_B_CPU1_SA_CS_N<0>
  VSS27  = GND
  CA0_A  = M_B_CPU1_SA_CA<0>
  VSS28  = GND
  CA2_A  = M_B_CPU1_SA_CA<2>
  VSS29  = GND
  CA4_A  = M_B_CPU1_SA_CA<4>
  VSS30  = GND
  CA6_A  = M_B_CPU1_SA_CA<6>
  VSS31  = GND
  PAR_A  = M_B_CPU1_SA_PAR
  VSS32  = GND
  CA0_B  = M_B_CPU1_SB_CA<0>
  VSS33  = GND
  CA2_B  = M_B_CPU1_SB_CA<2>
  VSS34  = GND
  CA4_B  = M_B_CPU1_SB_CA<4>
  VSS35  = GND
  CA6_B  = M_B_CPU1_SB_CA<6>
  VSS36  = GND
  CS0_B_N  = M_B_CPU1_SB_CS_N<0>
  VSS37  = GND
  \lbd||rsp_a_n\  = M_B_CPU1_SA_RSP<0>
  \lbs||rsp_b_n\  = M_B_CPU1_SB_RSP<0>
  VSS38  = GND
  CB4_B  = M_B_CPU1_SB_CB<4>
  VSS39  = GND
  CB5_B  = M_B_CPU1_SB_CB<5>
  VSS40  = GND
  \dqs9_b_t||tdqs9_b_t||dbi4_b_n\  = M_B_CPU1_SB_DQS_DP<9>
  \dqs9_b_c||tdqs9_b_c\  = M_B_CPU1_SB_DQS_DN<9>
  VSS41  = GND
  CB0_B  = M_B_CPU1_SB_CB<0>
  VSS42  = GND
  CB1_B  = M_B_CPU1_SB_CB<1>
  VSS43  = GND
  DQ0_B  = M_B_CPU1_SB_DQ<0>
  VSS44  = GND
  DQ1_B  = M_B_CPU1_SB_DQ<1>
  VSS45  = GND
  DQS0_B_T  = M_B_CPU1_SB_DQS_DP<0>
  DQS0_B_C  = M_B_CPU1_SB_DQS_DN<0>
  VSS46  = GND
  DQ4_B  = M_B_CPU1_SB_DQ<4>
  VSS47  = GND
  DQ5_B  = M_B_CPU1_SB_DQ<5>
  VSS48  = GND
  DQ8_B  = M_B_CPU1_SB_DQ<8>
  VSS49  = GND
  DQ9_B  = M_B_CPU1_SB_DQ<9>
  VSS50  = GND
  DQS1_B_T  = M_B_CPU1_SB_DQS_DP<1>
  DQS1_B_C  = M_B_CPU1_SB_DQS_DN<1>
  VSS51  = GND
  DQ12_B  = M_B_CPU1_SB_DQ<12>
  VSS52  = GND
  DQ13_B  = M_B_CPU1_SB_DQ<13>
  VSS53  = GND
  DQ16_B  = M_B_CPU1_SB_DQ<16>
  VSS54  = GND
  DQ17_B  = M_B_CPU1_SB_DQ<17>
  VSS55  = GND
  DQS2_B_T  = M_B_CPU1_SB_DQS_DP<2>
  DQS2_B_C  = M_B_CPU1_SB_DQS_DN<2>
  VSS56  = GND
  DQ20_B  = M_B_CPU1_SB_DQ<20>
  VSS57  = GND
  DQ21_B  = M_B_CPU1_SB_DQ<21>
  VSS58  = GND
  DQ24_B  = M_B_CPU1_SB_DQ<24>
  VSS59  = GND
  DQ25_B  = M_B_CPU1_SB_DQ<25>
  VSS60  = GND
  DQS3_B_T  = M_B_CPU1_SB_DQS_DP<3>
  DQS3_B_C  = M_B_CPU1_SB_DQS_DN<3>
  VSS61  = GND
  DQ28_B  = M_B_CPU1_SB_DQ<28>
  VSS62  = GND
  DQ29_B  = M_B_CPU1_SB_DQ<29>
  VSS63  = GND
  RFU1  = TP_CHB_CPU1_DIMM1_FRU_1
  VIN_BULK1  = P12V_S3_AUX_CPU1_NVDIMM
  VIN_BULK2  = P12V_S3_AUX_CPU1_NVDIMM
  \pwr_good||fail_n\  = PWRGD_CHB_CPU1_DIMM1
  HSA  = PD_CHB_CPU1_DIMM1_SAA
  RFU2  = TP_CHB_CPU1_DIMM1_FRU_2
  RFU3  = TP_CHB_CPU1_DIMM1_FRU_3
  VSS64  = GND
  DQ2_A  = M_B_CPU1_SA_DQ<2>
  VSS65  = GND
  DQ3_A  = M_B_CPU1_SA_DQ<3>
  VSS66  = GND
  \dqs5_a_c||tdqs5_a_c||dqs5_a_t||tdqs5_a_t\  = M_B_CPU1_SA_DQS_DN<5>
  \dqs5_a_t||tdqs5_a_t\  = M_B_CPU1_SA_DQS_DP<5>
  VSS67  = GND
  DQ6_A  = M_B_CPU1_SA_DQ<6>
  VSS68  = GND
  DQ7_A  = M_B_CPU1_SA_DQ<7>
  VSS69  = GND
  DQ10_A  = M_B_CPU1_SA_DQ<10>
  VSS70  = GND
  DQ11_A  = M_B_CPU1_SA_DQ<11>
  VSS71  = GND
  \dqs6_a_c||tdqs6_a_c||dqs6_a_t||tdqs6_a_t\  = M_B_CPU1_SA_DQS_DN<6>
  \dqs6_a_t||tdqs6_a_t\  = M_B_CPU1_SA_DQS_DP<6>
  VSS72  = GND
  DQ14_A  = M_B_CPU1_SA_DQ<14>
  VSS73  = GND
  DQ15_A  = M_B_CPU1_SA_DQ<15>
  VSS74  = GND
  DQ18_A  = M_B_CPU1_SA_DQ<18>
  VSS75  = GND
  DQ19_A  = M_B_CPU1_SA_DQ<19>
  VSS76  = GND
  \dqs7_a_c||tdqs7_a_c\  = M_B_CPU1_SA_DQS_DN<7>
  \dqs7_a_t||tdqs7_a_t\  = M_B_CPU1_SA_DQS_DP<7>
  VSS77  = GND
  DQ22_A  = M_B_CPU1_SA_DQ<22>
  VSS78  = GND
  DQ23_A  = M_B_CPU1_SA_DQ<23>
  VSS79  = GND
  DQ26_A  = M_B_CPU1_SA_DQ<26>
  VSS80  = GND
  DQ27_A  = M_B_CPU1_SA_DQ<27>
  VSS81  = GND
  \dqs8_a_c||tdqs8_a_c\  = M_B_CPU1_SA_DQS_DN<8>
  \dqs8_a_t||tdqs8_a_t\  = M_B_CPU1_SA_DQS_DP<8>
  VSS82  = GND
  DQ30_A  = M_B_CPU1_SA_DQ<30>
  VSS83  = GND
  DQ31_A  = M_B_CPU1_SA_DQ<31>
  VSS84  = GND
  CB2_A  = M_B_CPU1_SA_CB<2>
  VSS85  = GND
  CB3_A  = M_B_CPU1_SA_CB<3>
  VSS86  = GND
  \dqs9_a_c||tdqs9_a_c\  = M_B_CPU1_SA_DQS_DN<9>
  \dqs9_a_t||tdqs9_a_t\  = M_B_CPU1_SA_DQS_DP<9>
  VSS87  = GND
  CB6_A  = M_B_CPU1_SA_CB<6>
  VSS88  = GND
  CB7_A  = M_B_CPU1_SA_CB<7>
  VSS89  = GND
  RESET_N  = RST_M_AB_CPU1_FPGA_N
  VSS90  = GND
  CS1_A_N  = M_B_CPU1_SA_CS_N<1>
  VSS91  = GND
  CA1_A  = M_B_CPU1_SA_CA<1>
  VSS92  = GND
  CA3_A  = M_B_CPU1_SA_CA<3>
  VSS93  = GND
  CA5_A  = M_B_CPU1_SA_CA<5>
  VSS94  = GND
  CK_T  = M_B_CPU1_CLK_DP<0>
  CK_C  = M_B_CPU1_CLK_DN<0>
  VSS95  = GND
  RFU4  = TP_CHB_CPU1_DIMM1_FRU_4
  CA1_B  = M_B_CPU1_SB_CA<1>
  VSS96  = GND
  CA3_B  = M_B_CPU1_SB_CA<3>
  VSS97  = GND
  CA5_B  = M_B_CPU1_SB_CA<5>
  VSS98  = GND
  PAR_B  = M_B_CPU1_SB_PAR
  VSS99  = GND
  CS1_B_N  = M_B_CPU1_SB_CS_N<1>
  VSS100  = GND
  RFU5  = TP_CHB_CPU1_DIMM1_FRU_5
  RFU6  = TP_CHB_CPU1_DIMM1_FRU_6
  VSS101  = GND
  CB6_B  = M_B_CPU1_SB_CB<6>
  VSS102  = GND
  CB7_B  = M_B_CPU1_SB_CB<7>
  VSS103  = GND
  DQS4_B_C  = M_B_CPU1_SB_DQS_DN<4>
  DQS4_B_T  = M_B_CPU1_SB_DQS_DP<4>
  VSS104  = GND
  CB2_B  = M_B_CPU1_SB_CB<2>
  VSS105  = GND
  CB3_B  = M_B_CPU1_SB_CB<3>
  VSS106  = GND
  DQ2_B  = M_B_CPU1_SB_DQ<2>
  VSS107  = GND
  DQ3_B  = M_B_CPU1_SB_DQ<3>
  VSS108  = GND
  \dqs5_b_c||tdqs5_b_c\  = M_B_CPU1_SB_DQS_DN<5>
  \dqs5_b_t||tdqs5_b_t\  = M_B_CPU1_SB_DQS_DP<5>
  VSS109  = GND
  DQ6_B  = M_B_CPU1_SB_DQ<6>
  VSS110  = GND
  DQ7_B  = M_B_CPU1_SB_DQ<7>
  VSS111  = GND
  DQ10_B  = M_B_CPU1_SB_DQ<10>
  VSS112  = GND
  DQ11_B  = M_B_CPU1_SB_DQ<11>
  VSS113  = GND
  \dqs6_b_c||tdqs6_b_c\  = M_B_CPU1_SB_DQS_DN<6>
  \dqs6_b_t||tdqs6_b_t\  = M_B_CPU1_SB_DQS_DP<6>
  VSS114  = GND
  DQ14_B  = M_B_CPU1_SB_DQ<14>
  VSS115  = GND
  DQ15_B  = M_B_CPU1_SB_DQ<15>
  VSS116  = GND
  DQ18_B  = M_B_CPU1_SB_DQ<18>
  VSS117  = GND
  DQ19_B  = M_B_CPU1_SB_DQ<19>
  VSS118  = GND
  \dqs7_b_c||tdqs7_b_c\  = M_B_CPU1_SB_DQS_DN<7>
  \dqs7_b_t||tdqs7_b_t\  = M_B_CPU1_SB_DQS_DP<7>
  VSS119  = GND
  DQ22_B  = M_B_CPU1_SB_DQ<22>
  VSS120  = GND
  DQ23_B  = M_B_CPU1_SB_DQ<23>
  VSS121  = GND
  DQ26_B  = M_B_CPU1_SB_DQ<26>
  VSS122  = GND
  DQ27_B  = M_B_CPU1_SB_DQ<27>
  VSS123  = GND
  \dqs8_b_c||tdqs8_b_c\  = M_B_CPU1_SB_DQS_DN<8>
  \dqs8_b_t||tdqs8_b_t\  = M_B_CPU1_SB_DQS_DP<8>
  VSS124  = GND
  DQ30_B  = M_B_CPU1_SB_DQ<30>
  VSS125  = GND
  DQ31_B  = M_B_CPU1_SB_DQ<31>
  VSS126  = GND
  G1  = GND
  G2  = GND
  G3  = GND

(kicad_pcb
	(version 20260206)
	(generator "pcbnew")
	(generator_version "10.0")
	(general
		(thickness 1.6)
		(legacy_teardrops no)
	)
	(paper "A4")
	(title_block
		(title "03242023_DA0F0TMBIJ0_F0T_Motherboard_J_brd_V01_OCP.brd")
		(comment 1 "Grand Teton / footprint 2188 of 6105 (J19), pads 92-137 of 291")
	)
	(layers
		(0 "F.Cu" signal "TOP")
		(4 "In1.Cu" signal "GND")
		(6 "In2.Cu" signal "IN1")
		(8 "In3.Cu" signal "GND1")
		(10 "In4.Cu" signal "IN2")
		(12 "In5.Cu" signal "GND2")
		(14 "In6.Cu" signal "IN3")
		(16 "In7.Cu" signal "GND3")
		(18 "In8.Cu" signal "VCC")
		(20 "In9.Cu" signal "VCC1")
		(22 "In10.Cu" signal "GND4")
		(24 "In11.Cu" signal "IN4")
		(26 "In12.Cu" signal "GND5")
		(28 "In13.Cu" signal "IN5")
		(30 "In14.Cu" signal "GND6")
		(32 "In15.Cu" signal "IN6")
		(34 "In16.Cu" signal "GND7")
		(2 "B.Cu" signal "BOTTOM")
		(9 "F.Adhes" user "F.Adhesive")
		(11 "B.Adhes" user "B.Adhesive")
		(13 "F.Paste" user "Package Geometry/Pastemask Top")
		(15 "B.Paste" user "Package Geometry/Pastemask Bottom")
		(5 "F.SilkS" user "Ref Des/Silkscreen Top")
		(7 "B.SilkS" user "Ref Des/Silkscreen Bottom")
		(1 "F.Mask" user "Board Geometry/Soldermask Top")
		(3 "B.Mask" user "Board Geometry/Soldermask Bottom")
		(17 "Dwgs.User" user "User.Drawings")
		(19 "Cmts.User" user "User.Comments")
		(21 "Eco1.User" user "User.Eco1")
		(23 "Eco2.User" user "User.Eco2")
		(25 "Edge.Cuts" user "Board Geometry/Outline")
		(27 "Margin" user)
		(31 "F.CrtYd" user "Package Geometry/Place Bound Top")
		(29 "B.CrtYd" user "Package Geometry/Place Bound Bottom")
		(35 "F.Fab" user "Ref Des/Assembly Top")
		(33 "B.Fab" user "Ref Des/Assembly Bottom")
	)
	(footprint ""
		(layer "F.Cu")
		(at 40.36568 -258.091686)
		(property "Reference" "J19"
			(at -5.21716 -81.970372 0)
			(unlocked yes)
			(layer "F.SilkS")
			(effects
				(font
					(size 0.7874 0.5842)
					(thickness 0.1524)
				)
				(justify left)
			)
		)
		(property "Value" ""
			(at 0 0 0)
			(layer "F.Fab")
			(effects
				(font
					(size 1.27 1.27)
				)
			)
		)
		(duplicate_pad_numbers_are_jumpers no)
		(pad "92" smd rect
			(at -2.050034 19.12493 270)
			(size 0.519938 1.4986)
			(layers "F.Cu" "F.Mask" "F.Paste")
			(net "GND")
		)
		(pad "93" smd rect
			(at -2.050034 19.975068 270)
			(size 0.519938 1.4986)
			(layers "F.Cu" "F.Mask" "F.Paste")
			(net "M_B_CPU1_SB_DQS_DP<9>")
		)
		(pad "94" smd rect
			(at -2.050034 20.824952 270)
			(size 0.519938 1.4986)
			(layers "F.Cu" "F.Mask" "F.Paste")
			(net "M_B_CPU1_SB_DQS_DN<9>")
		)
		(pad "95" smd rect
			(at -2.050034 21.67509 270)
			(size 0.519938 1.4986)
			(layers "F.Cu" "F.Mask" "F.Paste")
			(net "GND")
		)
		(pad "96" smd rect
			(at -2.050034 22.524974 270)
			(size 0.519938 1.4986)
			(layers "F.Cu" "F.Mask" "F.Paste")
			(net "M_B_CPU1_SB_CB<0>")
		)
		(pad "97" smd rect
			(at -2.050034 23.375112 270)
			(size 0.519938 1.4986)
			(layers "F.Cu" "F.Mask" "F.Paste")
			(net "GND")
		)
		(pad "98" smd rect
			(at -2.050034 24.224996 270)
			(size 0.519938 1.4986)
			(layers "F.Cu" "F.Mask" "F.Paste")
			(net "M_B_CPU1_SB_CB<1>")
		)
		(pad "99" smd rect
			(at -2.050034 25.07488 270)
			(size 0.519938 1.4986)
			(layers "F.Cu" "F.Mask" "F.Paste")
			(net "GND")
		)
		(pad "100" smd rect
			(at -2.050034 25.925018 270)
			(size 0.519938 1.4986)
			(layers "F.Cu" "F.Mask" "F.Paste")
			(net "M_B_CPU1_SB_DQ<0>")
		)
		(pad "101" smd rect
			(at -2.050034 26.774902 270)
			(size 0.519938 1.4986)
			(layers "F.Cu" "F.Mask" "F.Paste")
			(net "GND")
		)
		(pad "102" smd rect
			(at -2.050034 27.62504 270)
			(size 0.519938 1.4986)
			(layers "F.Cu" "F.Mask" "F.Paste")
			(net "M_B_CPU1_SB_DQ<1>")
		)
		(pad "103" smd rect
			(at -2.050034 28.474924 270)
			(size 0.519938 1.4986)
			(layers "F.Cu" "F.Mask" "F.Paste")
			(net "GND")
		)
		(pad "104" smd rect
			(at -2.050034 29.325062 270)
			(size 0.519938 1.4986)
			(layers "F.Cu" "F.Mask" "F.Paste")
			(net "M_B_CPU1_SB_DQS_DP<0>")
		)
		(pad "105" smd rect
			(at -2.050034 30.174946 270)
			(size 0.519938 1.4986)
			(layers "F.Cu" "F.Mask" "F.Paste")
			(net "M_B_CPU1_SB_DQS_DN<0>")
		)
		(pad "106" smd rect
			(at -2.050034 31.025084 270)
			(size 0.519938 1.4986)
			(layers "F.Cu" "F.Mask" "F.Paste")
			(net "GND")
		)
		(pad "107" smd rect
			(at -2.050034 31.874968 270)
			(size 0.519938 1.4986)
			(layers "F.Cu" "F.Mask" "F.Paste")
			(net "M_B_CPU1_SB_DQ<4>")
		)
		(pad "108" smd rect
			(at -2.050034 32.725106 270)
			(size 0.519938 1.4986)
			(layers "F.Cu" "F.Mask" "F.Paste")
			(net "GND")
		)
		(pad "109" smd rect
			(at -2.050034 33.57499 270)
			(size 0.519938 1.4986)
			(layers "F.Cu" "F.Mask" "F.Paste")
			(net "M_B_CPU1_SB_DQ<5>")
		)
		(pad "110" smd rect
			(at -2.050034 34.425128 270)
			(size 0.519938 1.4986)
			(layers "F.Cu" "F.Mask" "F.Paste")
			(net "GND")
		)
		(pad "111" smd rect
			(at -2.050034 35.275012 270)
			(size 0.519938 1.4986)
			(layers "F.Cu" "F.Mask" "F.Paste")
			(net "M_B_CPU1_SB_DQ<8>")
		)
		(pad "112" smd rect
			(at -2.050034 36.124896 270)
			(size 0.519938 1.4986)
			(layers "F.Cu" "F.Mask" "F.Paste")
			(net "GND")
		)
		(pad "113" smd rect
			(at -2.050034 36.975034 270)
			(size 0.519938 1.4986)
			(layers "F.Cu" "F.Mask" "F.Paste")
			(net "M_B_CPU1_SB_DQ<9>")
		)
		(pad "114" smd rect
			(at -2.050034 37.824918 270)
			(size 0.519938 1.4986)
			(layers "F.Cu" "F.Mask" "F.Paste")
			(net "GND")
		)
		(pad "115" smd rect
			(at -2.050034 38.675056 270)
			(size 0.519938 1.4986)
			(layers "F.Cu" "F.Mask" "F.Paste")
			(net "M_B_CPU1_SB_DQS_DP<1>")
		)
		(pad "116" smd rect
			(at -2.050034 39.52494 270)
			(size 0.519938 1.4986)
			(layers "F.Cu" "F.Mask" "F.Paste")
			(net "M_B_CPU1_SB_DQS_DN<1>")
		)
		(pad "117" smd rect
			(at -2.050034 40.375078 270)
			(size 0.519938 1.4986)
			(layers "F.Cu" "F.Mask" "F.Paste")
			(net "GND")
		)
		(pad "118" smd rect
			(at -2.050034 41.224962 270)
			(size 0.519938 1.4986)
			(layers "F.Cu" "F.Mask" "F.Paste")
			(net "M_B_CPU1_SB_DQ<12>")
		)
		(pad "119" smd rect
			(at -2.050034 42.0751 270)
			(size 0.519938 1.4986)
			(layers "F.Cu" "F.Mask" "F.Paste")
			(net "GND")
		)
		(pad "120" smd rect
			(at -2.050034 42.924984 270)
			(size 0.519938 1.4986)
			(layers "F.Cu" "F.Mask" "F.Paste")
			(net "M_B_CPU1_SB_DQ<13>")
		)
		(pad "121" smd rect
			(at -2.050034 43.775122 270)
			(size 0.519938 1.4986)
			(layers "F.Cu" "F.Mask" "F.Paste")
			(net "GND")
		)
		(pad "122" smd rect
			(at -2.050034 44.625006 270)
			(size 0.519938 1.4986)
			(layers "F.Cu" "F.Mask" "F.Paste")
			(net "M_B_CPU1_SB_DQ<16>")
		)
		(pad "123" smd rect
			(at -2.050034 45.47489 270)
			(size 0.519938 1.4986)
			(layers "F.Cu" "F.Mask" "F.Paste")
			(net "GND")
		)
		(pad "124" smd rect
			(at -2.050034 46.325028 270)
			(size 0.519938 1.4986)
			(layers "F.Cu" "F.Mask" "F.Paste")
			(net "M_B_CPU1_SB_DQ<17>")
		)
		(pad "125" smd rect
			(at -2.050034 47.174912 270)
			(size 0.519938 1.4986)
			(layers "F.Cu" "F.Mask" "F.Paste")
			(net "GND")
		)
		(pad "126" smd rect
			(at -2.050034 48.02505 270)
			(size 0.519938 1.4986)
			(layers "F.Cu" "F.Mask" "F.Paste")
			(net "M_B_CPU1_SB_DQS_DP<2>")
		)
		(pad "127" smd rect
			(at -2.050034 48.874934 270)
			(size 0.519938 1.4986)
			(layers "F.Cu" "F.Mask" "F.Paste")
			(net "M_B_CPU1_SB_DQS_DN<2>")
		)
		(pad "128" smd rect
			(at -2.050034 49.725072 270)
			(size 0.519938 1.4986)
			(layers "F.Cu" "F.Mask" "F.Paste")
			(net "GND")
		)
		(pad "129" smd rect
			(at -2.050034 50.574956 270)
			(size 0.519938 1.4986)
			(layers "F.Cu" "F.Mask" "F.Paste")
			(net "M_B_CPU1_SB_DQ<20>")
		)
		(pad "130" smd rect
			(at -2.050034 51.425094 270)
			(size 0.519938 1.4986)
			(layers "F.Cu" "F.Mask" "F.Paste")
			(net "GND")
		)
		(pad "131" smd rect
			(at -2.050034 52.274978 270)
			(size 0.519938 1.4986)
			(layers "F.Cu" "F.Mask" "F.Paste")
			(net "M_B_CPU1_SB_DQ<21>")
		)
		(pad "132" smd rect
			(at -2.050034 53.125116 270)
			(size 0.519938 1.4986)
			(layers "F.Cu" "F.Mask" "F.Paste")
			(net "GND")
		)
		(pad "133" smd rect
			(at -2.050034 53.975 270)
			(size 0.519938 1.4986)
			(layers "F.Cu" "F.Mask" "F.Paste")
			(net "M_B_CPU1_SB_DQ<24>")
		)
		(pad "134" smd rect
			(at -2.050034 54.824884 270)
			(size 0.519938 1.4986)
			(layers "F.Cu" "F.Mask" "F.Paste")
			(net "GND")
		)
		(pad "135" smd rect
			(at -2.050034 55.675022 270)
			(size 0.519938 1.4986)
			(layers "F.Cu" "F.Mask" "F.Paste")
			(net "M_B_CPU1_SB_DQ<25>")
		)
		(pad "136" smd rect
			(at -2.050034 56.524906 270)
			(size 0.519938 1.4986)
			(layers "F.Cu" "F.Mask" "F.Paste")
			(net "GND")
		)
		(pad "137" smd rect
			(at -2.050034 57.375044 270)
			(size 0.519938 1.4986)
			(layers "F.Cu" "F.Mask" "F.Paste")
			(net "M_B_CPU1_SB_DQS_DP<3>")
		)
	)
)
